# S9S_MB_2U (Grand Teton) — schematic netlist excerpt (pin names and nets, part order shuffled) for the footprints in the layout excerpt that follows; sources: Cadence DE-HDL packaged netlist, KiCad conversion of 03242023_DA0F0TMBIJ0_F0T_Motherboard_J_brd_V01_OCP.brd

R1249  Q_RES  0 5% CHIP  pkg 0402LF  page 203 : A = FM_THERMTRIP_DLY_LVC1_N ; B = H_THERMTRIP_LVC1_N
PC624  Q_CAP  0.1UF 25V 10% X7R  pkg 0402  page 278 : A = PVCCD_HV_CPU0_ISENSE_P ; B = GND
C771  Q_CAP_DIFFBUS  DIFF BUS_0.22UF 6.3V 20% X6S  pkg C0201  page 176 : \1\ = P5E_CPU1_PE2_TX_C_DP<1> ; \2\ = P5E_CPU1_PE2_TX_DP<1>

(kicad_pcb
	(version 20260206)
	(generator "pcbnew")
	(generator_version "10.0")
	(general
		(thickness 1.6)
		(legacy_teardrops no)
	)
	(paper "A4")
	(title_block
		(title "03242023_DA0F0TMBIJ0_F0T_Motherboard_J_brd_V01_OCP.brd")
		(comment 1 "Grand Teton / footprints 2707-2709 of 6105")
	)
	(layers
		(0 "F.Cu" signal "TOP")
		(4 "In1.Cu" signal "GND")
		(6 "In2.Cu" signal "IN1")
		(8 "In3.Cu" signal "GND1")
		(10 "In4.Cu" signal "IN2")
		(12 "In5.Cu" signal "GND2")
		(14 "In6.Cu" signal "IN3")
		(16 "In7.Cu" signal "GND3")
		(18 "In8.Cu" signal "VCC")
		(20 "In9.Cu" signal "VCC1")
		(22 "In10.Cu" signal "GND4")
		(24 "In11.Cu" signal "IN4")
		(26 "In12.Cu" signal "GND5")
		(28 "In13.Cu" signal "IN5")
		(30 "In14.Cu" signal "GND6")
		(32 "In15.Cu" signal "IN6")
		(34 "In16.Cu" signal "GND7")
		(2 "B.Cu" signal "BOTTOM")
		(9 "F.Adhes" user "F.Adhesive")
		(11 "B.Adhes" user "B.Adhesive")
		(13 "F.Paste" user "Package Geometry/Pastemask Top")
		(15 "B.Paste" user "Package Geometry/Pastemask Bottom")
		(5 "F.SilkS" user "Ref Des/Silkscreen Top")
		(7 "B.SilkS" user "Ref Des/Silkscreen Bottom")
		(1 "F.Mask" user "Board Geometry/Soldermask Top")
		(3 "B.Mask" user "Board Geometry/Soldermask Bottom")
		(17 "Dwgs.User" user "User.Drawings")
		(19 "Cmts.User" user "User.Comments")
		(21 "Eco1.User" user "User.Eco1")
		(23 "Eco2.User" user "User.Eco2")
		(25 "Edge.Cuts" user "Board Geometry/Outline")
		(27 "Margin" user)
		(31 "F.CrtYd" user "Package Geometry/Place Bound Top")
		(29 "B.CrtYd" user "Package Geometry/Place Bound Bottom")
		(35 "F.Fab" user "Ref Des/Assembly Top")
		(33 "B.Fab" user "Ref Des/Assembly Bottom")
	)
	(footprint ""
		(layer "F.Cu")
		(at 163.014914 -402.371052 -90)
		(property "Reference" "C771"
			(at 0 0 270)
			(layer "F.SilkS")
			(hide yes)
			(effects
				(font
					(size 1.27 1.27)
				)
			)
		)
		(property "Value" ""
			(at 0 0 270)
			(layer "F.Fab")
			(effects
				(font
					(size 1.27 1.27)
				)
			)
		)
		(duplicate_pad_numbers_are_jumpers no)
		(fp_line
			(start -0.299974 0.150114)
			(end -0.299974 -0.150114)
			(stroke
				(width 0.1)
				(type default)
			)
			(layer "F.Fab")
		)
		(fp_line
			(start 0.299974 0.150114)
			(end -0.299974 0.150114)
			(stroke
				(width 0.1)
				(type default)
			)
			(layer "F.Fab")
		)
		(fp_line
			(start -0.299974 -0.150114)
			(end 0.299974 -0.150114)
			(stroke
				(width 0.1)
				(type default)
			)
			(layer "F.Fab")
		)
		(fp_line
			(start 0.299974 -0.150114)
			(end 0.299974 0.150114)
			(stroke
				(width 0.1)
				(type default)
			)
			(layer "F.Fab")
		)
		(pad "1" smd rect
			(at -0.2667 0 270)
			(size 0.3048 0.381)
			(layers "F.Cu" "F.Mask" "F.Paste")
			(net "P5E_CPU1_PE2_TX_C_DP<1>")
		)
		(pad "2" smd rect
			(at 0.2667 0 270)
			(size 0.3048 0.381)
			(layers "F.Cu" "F.Mask" "F.Paste")
			(net "P5E_CPU1_PE2_TX_DP<1>")
		)
	)
	(footprint ""
		(layer "F.Cu")
		(at 428.226474 -122.62866 180)
		(property "Reference" "PC624"
			(at 0 0 180)
			(layer "F.SilkS")
			(hide yes)
			(effects
				(font
					(size 1.27 1.27)
				)
			)
		)
		(property "Value" ""
			(at 0 0 180)
			(layer "F.Fab")
			(effects
				(font
					(size 1.27 1.27)
				)
			)
		)
		(duplicate_pad_numbers_are_jumpers no)
		(fp_line
			(start 0.7874 0.4064)
			(end -0.7874 0.4064)
			(stroke
				(width 0.1524)
				(type default)
			)
			(layer "F.SilkS")
		)
		(fp_line
			(start 0.7874 -0.4064)
			(end 0.7874 0.4064)
			(stroke
				(width 0.1524)
				(type default)
			)
			(layer "F.SilkS")
		)
		(fp_line
			(start -0.7874 0.4064)
			(end -0.7874 -0.4064)
			(stroke
				(width 0.1524)
				(type default)
			)
			(layer "F.SilkS")
		)
		(fp_line
			(start -0.7874 -0.4064)
			(end 0.7874 -0.4064)
			(stroke
				(width 0.1524)
				(type default)
			)
			(layer "F.SilkS")
		)
		(fp_line
			(start 0.67945 0.3048)
			(end 0.120396 0.3048)
			(stroke
				(width 0.1)
				(type default)
			)
			(layer "F.Fab")
		)
		(fp_line
			(start 0.67945 -0.3048)
			(end 0.67945 0.3048)
			(stroke
				(width 0.1)
				(type default)
			)
			(layer "F.Fab")
		)
		(fp_line
			(start 0.12065 -0.2794)
			(end 0.12065 -0.3048)
			(stroke
				(width 0.1)
				(type default)
			)
			(layer "F.Fab")
		)
		(fp_line
			(start 0.12065 -0.3048)
			(end 0.67945 -0.3048)
			(stroke
				(width 0.1)
				(type default)
			)
			(layer "F.Fab")
		)
		(fp_line
			(start 0.120396 0.3048)
			(end 0.120396 0.2794)
			(stroke
				(width 0.1)
				(type default)
			)
			(layer "F.Fab")
		)
		(fp_line
			(start 0.120396 0.2794)
			(end -0.12065 0.2794)
			(stroke
				(width 0.1)
				(type default)
			)
			(layer "F.Fab")
		)
		(fp_line
			(start -0.12065 0.3048)
			(end -0.67945 0.3048)
			(stroke
				(width 0.1)
				(type default)
			)
			(layer "F.Fab")
		)
		(fp_line
			(start -0.12065 0.2794)
			(end -0.12065 0.3048)
			(stroke
				(width 0.1)
				(type default)
			)
			(layer "F.Fab")
		)
		(fp_line
			(start -0.12065 -0.2794)
			(end 0.12065 -0.2794)
			(stroke
				(width 0.1)
				(type default)
			)
			(layer "F.Fab")
		)
		(fp_line
			(start -0.12065 -0.305054)
			(end -0.12065 -0.2794)
			(stroke
				(width 0.1)
				(type default)
			)
			(layer "F.Fab")
		)
		(fp_line
			(start -0.67945 0.3048)
			(end -0.67945 -0.305054)
			(stroke
				(width 0.1)
				(type default)
			)
			(layer "F.Fab")
		)
		(fp_line
			(start -0.67945 -0.305054)
			(end -0.12065 -0.305054)
			(stroke
				(width 0.1)
				(type default)
			)
			(layer "F.Fab")
		)
		(pad "1" smd circle
			(at -0.40005 0 180)
			(size 0 0)
			(layers "F.Cu" "F.Mask" "F.Paste")
			(net "PVCCD_HV_CPU0_ISENSE_P")
		)
		(pad "2" smd circle
			(at 0.40005 0 180)
			(size 0 0)
			(layers "F.Cu" "F.Mask" "F.Paste")
			(net "GND")
		)
	)
	(footprint ""
		(layer "F.Cu")
		(at 320.241422 -63.896748)
		(property "Reference" "R1249"
			(at 0 0 0)
			(layer "F.SilkS")
			(hide yes)
			(effects
				(font
					(size 1.27 1.27)
				)
			)
		)
		(property "Value" ""
			(at 0 0 0)
			(layer "F.Fab")
			(effects
				(font
					(size 1.27 1.27)
				)
			)
		)
		(duplicate_pad_numbers_are_jumpers no)
		(fp_line
			(start -0.7874 -0.4064)
			(end 0.7874 -0.4064)
			(stroke
				(width 0.1524)
				(type default)
			)
			(layer "F.SilkS")
		)
		(fp_line
			(start -0.7874 0.4064)
			(end -0.7874 -0.4064)
			(stroke
				(width 0.1524)
				(type default)
			)
			(layer "F.SilkS")
		)
		(fp_line
			(start 0.7874 -0.4064)
			(end 0.7874 0.4064)
			(stroke
				(width 0.1524)
				(type default)
			)
			(layer "F.SilkS")
		)
		(fp_line
			(start 0.7874 0.4064)
			(end -0.7874 0.4064)
			(stroke
				(width 0.1524)
				(type default)
			)
			(layer "F.SilkS")
		)
		(fp_line
			(start -0.67945 -0.305054)
			(end -0.12065 -0.305054)
			(stroke
				(width 0.1)
				(type default)
			)
			(layer "F.Fab")
		)
		(fp_line
			(start -0.67945 0.3048)
			(end -0.67945 -0.305054)
			(stroke
				(width 0.1)
				(type default)
			)
			(layer "F.Fab")
		)
		(fp_line
			(start -0.12065 -0.305054)
			(end -0.12065 -0.2794)
			(stroke
				(width 0.1)
				(type default)
			)
			(layer "F.Fab")
		)
		(fp_line
			(start -0.12065 -0.2794)
			(end 0.12065 -0.2794)
			(stroke
				(width 0.1)
				(type default)
			)
			(layer "F.Fab")
		)
		(fp_line
			(start -0.12065 0.2794)
			(end -0.12065 0.3048)
			(stroke
				(width 0.1)
				(type default)
			)
			(layer "F.Fab")
		)
		(fp_line
			(start -0.12065 0.3048)
			(end -0.67945 0.3048)
			(stroke
				(width 0.1)
				(type default)
			)
			(layer "F.Fab")
		)
		(fp_line
			(start 0.120396 0.2794)
			(end -0.12065 0.2794)
			(stroke
				(width 0.1)
				(type default)
			)
			(layer "F.Fab")
		)
		(fp_line
			(start 0.120396 0.3048)
			(end 0.120396 0.2794)
			(stroke
				(width 0.1)
				(type default)
			)
			(layer "F.Fab")
		)
		(fp_line
			(start 0.12065 -0.3048)
			(end 0.67945 -0.3048)
			(stroke
				(width 0.1)
				(type default)
			)
			(layer "F.Fab")
		)
		(fp_line
			(start 0.12065 -0.2794)
			(end 0.12065 -0.3048)
			(stroke
				(width 0.1)
				(type default)
			)
			(layer "F.Fab")
		)
		(fp_line
			(start 0.67945 -0.3048)
			(end 0.67945 0.3048)
			(stroke
				(width 0.1)
				(type default)
			)
			(layer "F.Fab")
		)
		(fp_line
			(start 0.67945 0.3048)
			(end 0.120396 0.3048)
			(stroke
				(width 0.1)
				(type default)
			)
			(layer "F.Fab")
		)
		(pad "1" smd circle
			(at -0.40005 0)
			(size 0 0)
			(layers "F.Cu" "F.Mask" "F.Paste")
			(net "FM_THERMTRIP_DLY_LVC1_N")
		)
		(pad "2" smd circle
			(at 0.40005 0)
			(size 0 0)
			(layers "F.Cu" "F.Mask" "F.Paste")
			(net "H_THERMTRIP_LVC1_N")
		)
	)
)
